# BASEBOARD_FAB2 (Tioga Pass) — schematic netlist excerpt (pin names and nets, part order shuffled) for the footprints in the layout excerpt that follows; sources: Cadence DE-HDL packaged netlist, KiCad conversion of Wiwynn_Tioga_Pass_MB.brd

C1T5  CAP_A  0.1UF 16V 10% X7R  pkg 0402V  page 139 : A = P0V9_LAN ; B = GND
R1M6  RES  0.0 5% CHIP  pkg 0402  page 176 : A = USB2_P01_DN ; B = USB2_P01_ESD_DN
R9T6  RES  15.0K 1% CHIP  pkg 0402  page 181 : A = P12V_PSU ; B = FM_P12V_HOTSWAP0_EN

(kicad_pcb
	(version 20260206)
	(generator "pcbnew")
	(generator_version "10.0")
	(general
		(thickness 1.6)
		(legacy_teardrops no)
	)
	(paper "A4")
	(title_block
		(title "Wiwynn_Tioga_Pass_MB.brd")
		(comment 1 "Tioga Pass / footprints 3056-3058 of 4770")
	)
	(layers
		(0 "F.Cu" signal "TOP")
		(4 "In1.Cu" signal "L2GND")
		(6 "In2.Cu" signal "L3")
		(8 "In3.Cu" signal "L4GND")
		(10 "In4.Cu" signal "L5")
		(12 "In5.Cu" signal "L6GND")
		(14 "In6.Cu" signal "L7VCC")
		(16 "In7.Cu" signal "L8VCC")
		(18 "In8.Cu" signal "L9GND")
		(20 "In9.Cu" signal "L10")
		(22 "In10.Cu" signal "L11GND")
		(24 "In11.Cu" signal "L12")
		(26 "In12.Cu" signal "L13GND")
		(2 "B.Cu" signal "BOTTOM")
		(9 "F.Adhes" user "F.Adhesive")
		(11 "B.Adhes" user "B.Adhesive")
		(13 "F.Paste" user "Package Geometry/Pastemask Top")
		(15 "B.Paste" user "Package Geometry/Pastemask Bottom")
		(5 "F.SilkS" user "Ref Des/Silkscreen Top")
		(7 "B.SilkS" user "Ref Des/Silkscreen Bottom")
		(1 "F.Mask" user "Board Geometry/Soldermask Top")
		(3 "B.Mask" user "Board Geometry/Soldermask Bottom")
		(17 "Dwgs.User" user "User.Drawings")
		(19 "Cmts.User" user "User.Comments")
		(21 "Eco1.User" user "User.Eco1")
		(23 "Eco2.User" user "User.Eco2")
		(25 "Edge.Cuts" user "Board Geometry/Outline")
		(27 "Margin" user)
		(31 "F.CrtYd" user "Package Geometry/Place Bound Top")
		(29 "B.CrtYd" user "Package Geometry/Place Bound Bottom")
		(35 "F.Fab" user "Ref Des/Assembly Top")
		(33 "B.Fab" user "Ref Des/Assembly Bottom")
	)
	(footprint ""
		(layer "B.Cu")
		(at 484.6574 -39.5986 180)
		(property "Reference" "C1T5"
			(at 0 0 0)
			(layer "B.SilkS")
			(hide yes)
			(effects
				(font
					(size 1.27 1.27)
				)
				(justify mirror)
			)
		)
		(property "Value" ""
			(at 0 0 0)
			(layer "B.Fab")
			(effects
				(font
					(size 1.27 1.27)
				)
				(justify mirror)
			)
		)
		(duplicate_pad_numbers_are_jumpers no)
		(fp_poly
			(pts
				(xy -0.3048 -0.1016) (xy -0.3048 0.9906) (xy 0.3048 0.9906) (xy 0.3048 -0.1016)
			)
			(stroke
				(width 0)
				(type default)
			)
			(fill no)
			(layer "B.CrtYd")
		)
		(fp_line
			(start 0.3048 0.9906)
			(end -0.3048 0.9906)
			(stroke
				(width 0.1)
				(type default)
			)
			(layer "B.Fab")
		)
		(fp_line
			(start 0.3048 -0.1016)
			(end 0.3048 0.9906)
			(stroke
				(width 0.1)
				(type default)
			)
			(layer "B.Fab")
		)
		(fp_line
			(start -0.3048 0.9906)
			(end -0.3048 -0.1016)
			(stroke
				(width 0.1)
				(type default)
			)
			(layer "B.Fab")
		)
		(fp_line
			(start -0.3048 -0.1016)
			(end 0.3048 -0.1016)
			(stroke
				(width 0.1)
				(type default)
			)
			(layer "B.Fab")
		)
		(pad "1" smd rect
			(at 0 0)
			(size 0.508 0.508)
			(layers "B.Cu" "B.Mask" "B.Paste")
			(net "P0V9_LAN")
		)
		(pad "2" smd rect
			(at 0 0.889)
			(size 0.508 0.508)
			(layers "B.Cu" "B.Mask" "B.Paste")
			(net "GND")
		)
		(zone
			(layer "B.Cu")
			(hatch none 0.5)
			(connect_pads
				(clearance 0)
			)
			(min_thickness 0.25)
			(keepout
				(tracks not_allowed)
				(vias allowed)
				(pads allowed)
				(copperpour not_allowed)
				(footprints allowed)
			)
			(placement
				(enabled no)
				(sheetname "")
			)
			(fill
				(thermal_gap 0.5)
				(thermal_bridge_width 0.5)
				(island_removal_mode 0)
			)
			(polygon
				(pts
					(xy 484.4034 -40.2336) (xy 484.9114 -40.2336) (xy 484.9114 -39.8526) (xy 484.4034 -39.8526)
				)
			)
		)
		(zone
			(layer "B.Cu")
			(hatch none 0.5)
			(connect_pads
				(clearance 0)
			)
			(min_thickness 0.25)
			(keepout
				(tracks allowed)
				(vias not_allowed)
				(pads allowed)
				(copperpour not_allowed)
				(footprints allowed)
			)
			(placement
				(enabled no)
				(sheetname "")
			)
			(fill
				(thermal_gap 0.5)
				(thermal_bridge_width 0.5)
				(island_removal_mode 0)
			)
			(polygon
				(pts
					(xy 484.4034 -39.8526) (xy 484.9114 -39.8526) (xy 484.9114 -40.2336) (xy 484.4034 -40.2336)
				)
			)
		)
	)
	(footprint ""
		(layer "B.Cu")
		(at 472.2368 -124.079 90)
		(property "Reference" "R1M6"
			(at 0 0 90)
			(layer "B.SilkS")
			(hide yes)
			(effects
				(font
					(size 1.27 1.27)
				)
				(justify mirror)
			)
		)
		(property "Value" ""
			(at 0 0 90)
			(layer "B.Fab")
			(effects
				(font
					(size 1.27 1.27)
				)
				(justify mirror)
			)
		)
		(duplicate_pad_numbers_are_jumpers no)
		(fp_rect
			(start -0.2794 -0.1016)
			(end 0.2794 0.9906)
			(stroke
				(width 0)
				(type default)
			)
			(fill no)
			(layer "B.CrtYd")
		)
		(fp_line
			(start 0.2794 -0.1016)
			(end 0.2794 0.9906)
			(stroke
				(width 0.1)
				(type default)
			)
			(layer "B.Fab")
		)
		(fp_line
			(start -0.2794 -0.1016)
			(end 0.2794 -0.1016)
			(stroke
				(width 0.1)
				(type default)
			)
			(layer "B.Fab")
		)
		(fp_line
			(start 0.2794 0.9906)
			(end -0.2794 0.9906)
			(stroke
				(width 0.1)
				(type default)
			)
			(layer "B.Fab")
		)
		(fp_line
			(start -0.2794 0.9906)
			(end -0.2794 -0.1016)
			(stroke
				(width 0.1)
				(type default)
			)
			(layer "B.Fab")
		)
		(pad "1" smd rect
			(at 0 0 270)
			(size 0.508 0.508)
			(layers "B.Cu" "B.Mask" "B.Paste")
			(net "USB2_P01_DN")
		)
		(pad "2" smd rect
			(at 0 0.889 270)
			(size 0.508 0.508)
			(layers "B.Cu" "B.Mask" "B.Paste")
			(net "USB2_P01_ESD_DN")
		)
		(zone
			(layer "B.Cu")
			(hatch none 0.5)
			(connect_pads
				(clearance 0)
			)
			(min_thickness 0.25)
			(keepout
				(tracks allowed)
				(vias not_allowed)
				(pads allowed)
				(copperpour not_allowed)
				(footprints allowed)
			)
			(placement
				(enabled no)
				(sheetname "")
			)
			(fill
				(thermal_gap 0.5)
				(thermal_bridge_width 0.5)
				(island_removal_mode 0)
			)
			(polygon
				(pts
					(xy 472.4908 -123.825) (xy 472.8718 -123.825) (xy 472.8718 -124.333) (xy 472.4908 -124.333)
				)
			)
		)
		(zone
			(layer "B.Cu")
			(hatch none 0.5)
			(connect_pads
				(clearance 0)
			)
			(min_thickness 0.25)
			(keepout
				(tracks not_allowed)
				(vias allowed)
				(pads allowed)
				(copperpour not_allowed)
				(footprints allowed)
			)
			(placement
				(enabled no)
				(sheetname "")
			)
			(fill
				(thermal_gap 0.5)
				(thermal_bridge_width 0.5)
				(island_removal_mode 0)
			)
			(polygon
				(pts
					(xy 472.4908 -123.825) (xy 472.8718 -123.825) (xy 472.8718 -124.333) (xy 472.4908 -124.333)
				)
			)
		)
	)
	(footprint ""
		(layer "B.Cu")
		(at 24.765 -30.099 -90)
		(property "Reference" "R9T6"
			(at 0 0 90)
			(layer "B.SilkS")
			(hide yes)
			(effects
				(font
					(size 1.27 1.27)
				)
				(justify mirror)
			)
		)
		(property "Value" ""
			(at 0 0 90)
			(layer "B.Fab")
			(effects
				(font
					(size 1.27 1.27)
				)
				(justify mirror)
			)
		)
		(duplicate_pad_numbers_are_jumpers no)
		(fp_rect
			(start 0.2794 0.9906)
			(end -0.2794 -0.1016)
			(stroke
				(width 0)
				(type default)
			)
			(fill no)
			(layer "B.CrtYd")
		)
		(fp_line
			(start -0.2794 0.9906)
			(end -0.2794 -0.1016)
			(stroke
				(width 0.1)
				(type default)
			)
			(layer "B.Fab")
		)
		(fp_line
			(start 0.2794 0.9906)
			(end -0.2794 0.9906)
			(stroke
				(width 0.1)
				(type default)
			)
			(layer "B.Fab")
		)
		(fp_line
			(start -0.2794 -0.1016)
			(end 0.2794 -0.1016)
			(stroke
				(width 0.1)
				(type default)
			)
			(layer "B.Fab")
		)
		(fp_line
			(start 0.2794 -0.1016)
			(end 0.2794 0.9906)
			(stroke
				(width 0.1)
				(type default)
			)
			(layer "B.Fab")
		)
		(pad "1" smd rect
			(at 0 0 90)
			(size 0.508 0.508)
			(layers "B.Cu" "B.Mask" "B.Paste")
			(net "P12V_PSU")
		)
		(pad "2" smd rect
			(at 0 0.889 90)
			(size 0.508 0.508)
			(layers "B.Cu" "B.Mask" "B.Paste")
			(net "FM_P12V_HOTSWAP0_EN")
		)
		(zone
			(layer "B.Cu")
			(hatch none 0.5)
			(connect_pads
				(clearance 0)
			)
			(min_thickness 0.25)
			(keepout
				(tracks not_allowed)
				(vias allowed)
				(pads allowed)
				(copperpour not_allowed)
				(footprints allowed)
			)
			(placement
				(enabled no)
				(sheetname "")
			)
			(fill
				(thermal_gap 0.5)
				(thermal_bridge_width 0.5)
				(island_removal_mode 0)
			)
			(polygon
				(pts
					(xy 24.13 -29.845) (xy 24.511 -29.845) (xy 24.511 -30.353) (xy 24.13 -30.353)
				)
			)
		)
		(zone
			(layer "B.Cu")
			(hatch none 0.5)
			(connect_pads
				(clearance 0)
			)
			(min_thickness 0.25)
			(keepout
				(tracks allowed)
				(vias not_allowed)
				(pads allowed)
				(copperpour not_allowed)
				(footprints allowed)
			)
			(placement
				(enabled no)
				(sheetname "")
			)
			(fill
				(thermal_gap 0.5)
				(thermal_bridge_width 0.5)
				(island_removal_mode 0)
			)
			(polygon
				(pts
					(xy 24.13 -29.845) (xy 24.511 -29.845) (xy 24.511 -30.353) (xy 24.13 -30.353)
				)
			)
		)
	)
)
